# T6G (Grand Teton) — schematic netlist excerpt (pin names and nets, part order shuffled) for the footprints in the layout excerpt that follows; sources: Cadence DE-HDL packaged netlist, KiCad conversion of 04192023_DAF0TMB3IC0_F0TG_MB_C_brd_V02_OCP.brd

R447  Q_RES  4.7K 5% CHIP  pkg 0402LF  page 28 : A = IRQ_TPM_SPI_R_N ; B = PVDD18_S5_P0
PR6811  Q_RES  0 5% CHIP  pkg 0402LF  page 364 : A = P0V9_RETIMER_CPU1_SVID_CLK ; B = GND
PC129_3  Q_CAP  22UF 4V 20% X6S  pkg C0805  page 202 : A = PVDDCR_CPU1_P0 ; B = GND

(kicad_pcb
	(version 20260206)
	(generator "pcbnew")
	(generator_version "10.0")
	(general
		(thickness 1.6)
		(legacy_teardrops no)
	)
	(paper "A4")
	(title_block
		(title "04192023_DAF0TMB3IC0_F0TG_MB_C_brd_V02_OCP.brd")
		(comment 1 "Grand Teton / footprints 8076-8078 of 8354")
	)
	(layers
		(0 "F.Cu" signal "TOP")
		(4 "In1.Cu" signal "GND")
		(6 "In2.Cu" signal "IN1")
		(8 "In3.Cu" signal "GND1")
		(10 "In4.Cu" signal "IN2")
		(12 "In5.Cu" signal "GND2")
		(14 "In6.Cu" signal "IN3")
		(16 "In7.Cu" signal "GND3")
		(18 "In8.Cu" signal "VCC")
		(20 "In9.Cu" signal "VCC1")
		(22 "In10.Cu" signal "GND4")
		(24 "In11.Cu" signal "IN4")
		(26 "In12.Cu" signal "GND5")
		(28 "In13.Cu" signal "IN5")
		(30 "In14.Cu" signal "GND6")
		(32 "In15.Cu" signal "IN6")
		(34 "In16.Cu" signal "GND7")
		(2 "B.Cu" signal "BOTTOM")
		(9 "F.Adhes" user "F.Adhesive")
		(11 "B.Adhes" user "B.Adhesive")
		(13 "F.Paste" user "Package Geometry/Pastemask Top")
		(15 "B.Paste" user "Package Geometry/Pastemask Bottom")
		(5 "F.SilkS" user "Ref Des/Silkscreen Top")
		(7 "B.SilkS" user "Ref Des/Silkscreen Bottom")
		(1 "F.Mask" user "Board Geometry/Soldermask Top")
		(3 "B.Mask" user "Board Geometry/Soldermask Bottom")
		(17 "Dwgs.User" user "User.Drawings")
		(19 "Cmts.User" user "User.Comments")
		(21 "Eco1.User" user "User.Eco1")
		(23 "Eco2.User" user "User.Eco2")
		(25 "Edge.Cuts" user "Board Geometry/Outline")
		(27 "Margin" user)
		(31 "F.CrtYd" user "Package Geometry/Place Bound Top")
		(29 "B.CrtYd" user "Package Geometry/Place Bound Bottom")
		(35 "F.Fab" user "Ref Des/Assembly Top")
		(33 "B.Fab" user "Ref Des/Assembly Bottom")
	)
	(footprint ""
		(layer "B.Cu")
		(at 402.322538 -320.189352 180)
		(property "Reference" "R447"
			(at 0 0 0)
			(layer "B.SilkS")
			(hide yes)
			(effects
				(font
					(size 1.27 1.27)
				)
				(justify mirror)
			)
		)
		(property "Value" ""
			(at 0 0 0)
			(layer "B.Fab")
			(effects
				(font
					(size 1.27 1.27)
				)
				(justify mirror)
			)
		)
		(duplicate_pad_numbers_are_jumpers no)
		(fp_line
			(start 0.7874 0.4064)
			(end 0.7874 -0.4064)
			(stroke
				(width 0.1524)
				(type default)
			)
			(layer "B.SilkS")
		)
		(fp_line
			(start 0.7874 -0.4064)
			(end -0.7874 -0.4064)
			(stroke
				(width 0.1524)
				(type default)
			)
			(layer "B.SilkS")
		)
		(fp_line
			(start -0.7874 0.4064)
			(end 0.7874 0.4064)
			(stroke
				(width 0.1524)
				(type default)
			)
			(layer "B.SilkS")
		)
		(fp_line
			(start -0.7874 -0.4064)
			(end -0.7874 0.4064)
			(stroke
				(width 0.1524)
				(type default)
			)
			(layer "B.SilkS")
		)
		(fp_line
			(start 0.67945 0.3048)
			(end 0.67945 -0.305054)
			(stroke
				(width 0.1)
				(type default)
			)
			(layer "B.Fab")
		)
		(fp_line
			(start 0.67945 -0.305054)
			(end 0.12065 -0.305054)
			(stroke
				(width 0.1)
				(type default)
			)
			(layer "B.Fab")
		)
		(fp_line
			(start 0.12065 0.3048)
			(end 0.67945 0.3048)
			(stroke
				(width 0.1)
				(type default)
			)
			(layer "B.Fab")
		)
		(fp_line
			(start 0.12065 0.2794)
			(end 0.12065 0.3048)
			(stroke
				(width 0.1)
				(type default)
			)
			(layer "B.Fab")
		)
		(fp_line
			(start 0.12065 -0.2794)
			(end -0.12065 -0.2794)
			(stroke
				(width 0.1)
				(type default)
			)
			(layer "B.Fab")
		)
		(fp_line
			(start 0.12065 -0.305054)
			(end 0.12065 -0.2794)
			(stroke
				(width 0.1)
				(type default)
			)
			(layer "B.Fab")
		)
		(fp_line
			(start -0.120396 0.3048)
			(end -0.120396 0.2794)
			(stroke
				(width 0.1)
				(type default)
			)
			(layer "B.Fab")
		)
		(fp_line
			(start -0.120396 0.2794)
			(end 0.12065 0.2794)
			(stroke
				(width 0.1)
				(type default)
			)
			(layer "B.Fab")
		)
		(fp_line
			(start -0.12065 -0.2794)
			(end -0.12065 -0.3048)
			(stroke
				(width 0.1)
				(type default)
			)
			(layer "B.Fab")
		)
		(fp_line
			(start -0.12065 -0.3048)
			(end -0.67945 -0.3048)
			(stroke
				(width 0.1)
				(type default)
			)
			(layer "B.Fab")
		)
		(fp_line
			(start -0.67945 0.3048)
			(end -0.120396 0.3048)
			(stroke
				(width 0.1)
				(type default)
			)
			(layer "B.Fab")
		)
		(fp_line
			(start -0.67945 -0.3048)
			(end -0.67945 0.3048)
			(stroke
				(width 0.1)
				(type default)
			)
			(layer "B.Fab")
		)
		(pad "1" smd circle
			(at 0.40005 0)
			(size 0 0)
			(layers "B.Cu" "B.Mask" "B.Paste")
			(net "IRQ_TPM_SPI_R_N")
		)
		(pad "2" smd circle
			(at -0.40005 0)
			(size 0 0)
			(layers "B.Cu" "B.Mask" "B.Paste")
			(net "PVDD18_S5_P0")
		)
	)
	(footprint ""
		(layer "B.Cu")
		(at 20.480782 -410.564584 180)
		(property "Reference" "PR6811"
			(at 0 0 0)
			(layer "B.SilkS")
			(hide yes)
			(effects
				(font
					(size 1.27 1.27)
				)
				(justify mirror)
			)
		)
		(property "Value" ""
			(at 0 0 0)
			(layer "B.Fab")
			(effects
				(font
					(size 1.27 1.27)
				)
				(justify mirror)
			)
		)
		(duplicate_pad_numbers_are_jumpers no)
		(fp_line
			(start 0.7874 0.4064)
			(end 0.7874 -0.4064)
			(stroke
				(width 0.1524)
				(type default)
			)
			(layer "B.SilkS")
		)
		(fp_line
			(start 0.7874 -0.4064)
			(end -0.7874 -0.4064)
			(stroke
				(width 0.1524)
				(type default)
			)
			(layer "B.SilkS")
		)
		(fp_line
			(start -0.7874 0.4064)
			(end 0.7874 0.4064)
			(stroke
				(width 0.1524)
				(type default)
			)
			(layer "B.SilkS")
		)
		(fp_line
			(start -0.7874 -0.4064)
			(end -0.7874 0.4064)
			(stroke
				(width 0.1524)
				(type default)
			)
			(layer "B.SilkS")
		)
		(fp_line
			(start 0.67945 0.3048)
			(end 0.67945 -0.305054)
			(stroke
				(width 0.1)
				(type default)
			)
			(layer "B.Fab")
		)
		(fp_line
			(start 0.67945 -0.305054)
			(end 0.12065 -0.305054)
			(stroke
				(width 0.1)
				(type default)
			)
			(layer "B.Fab")
		)
		(fp_line
			(start 0.12065 0.3048)
			(end 0.67945 0.3048)
			(stroke
				(width 0.1)
				(type default)
			)
			(layer "B.Fab")
		)
		(fp_line
			(start 0.12065 0.2794)
			(end 0.12065 0.3048)
			(stroke
				(width 0.1)
				(type default)
			)
			(layer "B.Fab")
		)
		(fp_line
			(start 0.12065 -0.2794)
			(end -0.12065 -0.2794)
			(stroke
				(width 0.1)
				(type default)
			)
			(layer "B.Fab")
		)
		(fp_line
			(start 0.12065 -0.305054)
			(end 0.12065 -0.2794)
			(stroke
				(width 0.1)
				(type default)
			)
			(layer "B.Fab")
		)
		(fp_line
			(start -0.120396 0.3048)
			(end -0.120396 0.2794)
			(stroke
				(width 0.1)
				(type default)
			)
			(layer "B.Fab")
		)
		(fp_line
			(start -0.120396 0.2794)
			(end 0.12065 0.2794)
			(stroke
				(width 0.1)
				(type default)
			)
			(layer "B.Fab")
		)
		(fp_line
			(start -0.12065 -0.2794)
			(end -0.12065 -0.3048)
			(stroke
				(width 0.1)
				(type default)
			)
			(layer "B.Fab")
		)
		(fp_line
			(start -0.12065 -0.3048)
			(end -0.67945 -0.3048)
			(stroke
				(width 0.1)
				(type default)
			)
			(layer "B.Fab")
		)
		(fp_line
			(start -0.67945 0.3048)
			(end -0.120396 0.3048)
			(stroke
				(width 0.1)
				(type default)
			)
			(layer "B.Fab")
		)
		(fp_line
			(start -0.67945 -0.3048)
			(end -0.67945 0.3048)
			(stroke
				(width 0.1)
				(type default)
			)
			(layer "B.Fab")
		)
		(pad "1" smd circle
			(at 0.40005 0)
			(size 0 0)
			(layers "B.Cu" "B.Mask" "B.Paste")
			(net "P0V9_RETIMER_CPU1_SVID_CLK")
		)
		(pad "2" smd circle
			(at -0.40005 0)
			(size 0 0)
			(layers "B.Cu" "B.Mask" "B.Paste")
			(net "GND")
		)
	)
	(footprint ""
		(layer "B.Cu")
		(at 309.574184 -338.086446 -90)
		(property "Reference" "PC129_3"
			(at 0 0 90)
			(layer "B.SilkS")
			(hide yes)
			(effects
				(font
					(size 1.27 1.27)
				)
				(justify mirror)
			)
		)
		(property "Value" ""
			(at 0 0 90)
			(layer "B.Fab")
			(effects
				(font
					(size 1.27 1.27)
				)
				(justify mirror)
			)
		)
		(duplicate_pad_numbers_are_jumpers no)
		(fp_line
			(start -1.524 0.762)
			(end 1.524 0.762)
			(stroke
				(width 0.1524)
				(type default)
			)
			(layer "B.SilkS")
		)
		(fp_line
			(start 1.524 0.762)
			(end 1.524 -0.762)
			(stroke
				(width 0.1524)
				(type default)
			)
			(layer "B.SilkS")
		)
		(fp_line
			(start -1.524 -0.762)
			(end -1.524 0.762)
			(stroke
				(width 0.1524)
				(type default)
			)
			(layer "B.SilkS")
		)
		(fp_line
			(start 1.524 -0.762)
			(end -1.524 -0.762)
			(stroke
				(width 0.1524)
				(type default)
			)
			(layer "B.SilkS")
		)
		(fp_line
			(start -1.1049 0.724916)
			(end -1.1049 -0.724916)
			(stroke
				(width 0.1)
				(type default)
			)
			(layer "B.Fab")
		)
		(fp_line
			(start 1.1049 0.724916)
			(end -1.1049 0.724916)
			(stroke
				(width 0.1)
				(type default)
			)
			(layer "B.Fab")
		)
		(fp_line
			(start -1.1049 -0.724916)
			(end 1.1049 -0.724916)
			(stroke
				(width 0.1)
				(type default)
			)
			(layer "B.Fab")
		)
		(fp_line
			(start 1.1049 -0.724916)
			(end 1.1049 0.724916)
			(stroke
				(width 0.1)
				(type default)
			)
			(layer "B.Fab")
		)
		(pad "1" smd rect
			(at 0.889 0 270)
			(size 1.016 1.27)
			(layers "B.Cu" "B.Mask" "B.Paste")
			(net "PVDDCR_CPU1_P0")
		)
		(pad "2" smd rect
			(at -0.889 0 270)
			(size 1.016 1.27)
			(layers "B.Cu" "B.Mask" "B.Paste")
			(net "GND")
		)
	)
)
